(kicad_pcb
	(version 20260206)
	(generator "pcbnew")
	(generator_version "10.0")
	(general
		(thickness 1.6)
		(legacy_teardrops no)
	)
	(paper "A4")
	(title_block
		(title "04192023_DAF0TMB3IC0_F0TG_MB_C_brd_V02_OCP.brd")
		(comment 1 "Grand Teton / footprints 7321-7327 of 8354")
	)
	(layers
		(0 "F.Cu" signal "TOP")
		(4 "In1.Cu" signal "GND")
		(6 "In2.Cu" signal "IN1")
		(8 "In3.Cu" signal "GND1")
		(10 "In4.Cu" signal "IN2")
		(12 "In5.Cu" signal "GND2")
		(14 "In6.Cu" signal "IN3")
		(16 "In7.Cu" signal "GND3")
		(18 "In8.Cu" signal "VCC")
		(20 "In9.Cu" signal "VCC1")
		(22 "In10.Cu" signal "GND4")
		(24 "In11.Cu" signal "IN4")
		(26 "In12.Cu" signal "GND5")
		(28 "In13.Cu" signal "IN5")
		(30 "In14.Cu" signal "GND6")
		(32 "In15.Cu" signal "IN6")
		(34 "In16.Cu" signal "GND7")
		(2 "B.Cu" signal "BOTTOM")
		(9 "F.Adhes" user "F.Adhesive")
		(11 "B.Adhes" user "B.Adhesive")
		(13 "F.Paste" user "Package Geometry/Pastemask Top")
		(15 "B.Paste" user "Package Geometry/Pastemask Bottom")
		(5 "F.SilkS" user "Ref Des/Silkscreen Top")
		(7 "B.SilkS" user "Ref Des/Silkscreen Bottom")
		(1 "F.Mask" user "Board Geometry/Soldermask Top")
		(3 "B.Mask" user "Board Geometry/Soldermask Bottom")
		(17 "Dwgs.User" user "User.Drawings")
		(19 "Cmts.User" user "User.Comments")
		(21 "Eco1.User" user "User.Eco1")
		(23 "Eco2.User" user "User.Eco2")
		(25 "Edge.Cuts" user "Board Geometry/Outline")
		(27 "Margin" user)
		(31 "F.CrtYd" user "Package Geometry/Place Bound Top")
		(29 "B.CrtYd" user "Package Geometry/Place Bound Bottom")
		(35 "F.Fab" user "Ref Des/Assembly Top")
		(33 "B.Fab" user "Ref Des/Assembly Bottom")
	)
	(footprint ""
		(layer "B.Cu")
		(at 150.618952 -390.560052 90)
		(property "Reference" "C429"
			(at 0 0 90)
			(layer "B.SilkS")
			(hide yes)
			(effects
				(font
					(size 1.27 1.27)
				)
				(justify mirror)
			)
		)
		(property "Value" ""
			(at 0 0 90)
			(layer "B.Fab")
			(effects
				(font
					(size 1.27 1.27)
				)
				(justify mirror)
			)
		)
		(duplicate_pad_numbers_are_jumpers no)
		(fp_line
			(start 0.7874 -0.4064)
			(end -0.7874 -0.4064)
			(stroke
				(width 0.1524)
				(type default)
			)
			(layer "B.SilkS")
		)
		(fp_line
			(start -0.7874 -0.4064)
			(end -0.7874 0.4064)
			(stroke
				(width 0.1524)
				(type default)
			)
			(layer "B.SilkS")
		)
		(fp_line
			(start 0.7874 0.4064)
			(end 0.7874 -0.4064)
			(stroke
				(width 0.1524)
				(type default)
			)
			(layer "B.SilkS")
		)
		(fp_line
			(start -0.7874 0.4064)
			(end 0.7874 0.4064)
			(stroke
				(width 0.1524)
				(type default)
			)
			(layer "B.SilkS")
		)
		(fp_line
			(start 0.67945 -0.305054)
			(end 0.12065 -0.305054)
			(stroke
				(width 0.1)
				(type default)
			)
			(layer "B.Fab")
		)
		(fp_line
			(start 0.12065 -0.305054)
			(end 0.12065 -0.2794)
			(stroke
				(width 0.1)
				(type default)
			)
			(layer "B.Fab")
		)
		(fp_line
			(start -0.12065 -0.3048)
			(end -0.67945 -0.3048)
			(stroke
				(width 0.1)
				(type default)
			)
			(layer "B.Fab")
		)
		(fp_line
			(start -0.67945 -0.3048)
			(end -0.67945 0.3048)
			(stroke
				(width 0.1)
				(type default)
			)
			(layer "B.Fab")
		)
		(fp_line
			(start 0.12065 -0.2794)
			(end -0.12065 -0.2794)
			(stroke
				(width 0.1)
				(type default)
			)
			(layer "B.Fab")
		)
		(fp_line
			(start -0.12065 -0.2794)
			(end -0.12065 -0.3048)
			(stroke
				(width 0.1)
				(type default)
			)
			(layer "B.Fab")
		)
		(fp_line
			(start 0.12065 0.2794)
			(end 0.12065 0.3048)
			(stroke
				(width 0.1)
				(type default)
			)
			(layer "B.Fab")
		)
		(fp_line
			(start -0.120396 0.2794)
			(end 0.12065 0.2794)
			(stroke
				(width 0.1)
				(type default)
			)
			(layer "B.Fab")
		)
		(fp_line
			(start 0.67945 0.3048)
			(end 0.67945 -0.305054)
			(stroke
				(width 0.1)
				(type default)
			)
			(layer "B.Fab")
		)
		(fp_line
			(start 0.12065 0.3048)
			(end 0.67945 0.3048)
			(stroke
				(width 0.1)
				(type default)
			)
			(layer "B.Fab")
		)
		(fp_line
			(start -0.120396 0.3048)
			(end -0.120396 0.2794)
			(stroke
				(width 0.1)
				(type default)
			)
			(layer "B.Fab")
		)
		(fp_line
			(start -0.67945 0.3048)
			(end -0.120396 0.3048)
			(stroke
				(width 0.1)
				(type default)
			)
			(layer "B.Fab")
		)
		(pad "1" smd circle
			(at 0.40005 0 270)
			(size 0 0)
			(layers "B.Cu" "B.Mask" "B.Paste")
			(net "P0V9_CPU1_RT2_2A")
		)
		(pad "2" smd circle
			(at -0.40005 0 270)
			(size 0 0)
			(layers "B.Cu" "B.Mask" "B.Paste")
			(net "GND")
		)
	)
	(footprint ""
		(layer "B.Cu")
		(at 126.375668 -36.46043)
		(property "Reference" "C6073"
			(at 0 0 0)
			(layer "B.SilkS")
			(hide yes)
			(effects
				(font
					(size 1.27 1.27)
				)
				(justify mirror)
			)
		)
		(property "Value" ""
			(at 0 0 0)
			(layer "B.Fab")
			(effects
				(font
					(size 1.27 1.27)
				)
				(justify mirror)
			)
		)
		(duplicate_pad_numbers_are_jumpers no)
		(fp_line
			(start -0.7874 -0.4064)
			(end -0.7874 0.4064)
			(stroke
				(width 0.1524)
				(type default)
			)
			(layer "B.SilkS")
		)
		(fp_line
			(start -0.7874 0.4064)
			(end 0.7874 0.4064)
			(stroke
				(width 0.1524)
				(type default)
			)
			(layer "B.SilkS")
		)
		(fp_line
			(start 0.7874 -0.4064)
			(end -0.7874 -0.4064)
			(stroke
				(width 0.1524)
				(type default)
			)
			(layer "B.SilkS")
		)
		(fp_line
			(start 0.7874 0.4064)
			(end 0.7874 -0.4064)
			(stroke
				(width 0.1524)
				(type default)
			)
			(layer "B.SilkS")
		)
		(fp_line
			(start -0.67945 -0.3048)
			(end -0.67945 0.3048)
			(stroke
				(width 0.1)
				(type default)
			)
			(layer "B.Fab")
		)
		(fp_line
			(start -0.67945 0.3048)
			(end -0.120396 0.3048)
			(stroke
				(width 0.1)
				(type default)
			)
			(layer "B.Fab")
		)
		(fp_line
			(start -0.12065 -0.3048)
			(end -0.67945 -0.3048)
			(stroke
				(width 0.1)
				(type default)
			)
			(layer "B.Fab")
		)
		(fp_line
			(start -0.12065 -0.2794)
			(end -0.12065 -0.3048)
			(stroke
				(width 0.1)
				(type default)
			)
			(layer "B.Fab")
		)
		(fp_line
			(start -0.120396 0.2794)
			(end 0.12065 0.2794)
			(stroke
				(width 0.1)
				(type default)
			)
			(layer "B.Fab")
		)
		(fp_line
			(start -0.120396 0.3048)
			(end -0.120396 0.2794)
			(stroke
				(width 0.1)
				(type default)
			)
			(layer "B.Fab")
		)
		(fp_line
			(start 0.12065 -0.305054)
			(end 0.12065 -0.2794)
			(stroke
				(width 0.1)
				(type default)
			)
			(layer "B.Fab")
		)
		(fp_line
			(start 0.12065 -0.2794)
			(end -0.12065 -0.2794)
			(stroke
				(width 0.1)
				(type default)
			)
			(layer "B.Fab")
		)
		(fp_line
			(start 0.12065 0.2794)
			(end 0.12065 0.3048)
			(stroke
				(width 0.1)
				(type default)
			)
			(layer "B.Fab")
		)
		(fp_line
			(start 0.12065 0.3048)
			(end 0.67945 0.3048)
			(stroke
				(width 0.1)
				(type default)
			)
			(layer "B.Fab")
		)
		(fp_line
			(start 0.67945 -0.305054)
			(end 0.12065 -0.305054)
			(stroke
				(width 0.1)
				(type default)
			)
			(layer "B.Fab")
		)
		(fp_line
			(start 0.67945 0.3048)
			(end 0.67945 -0.305054)
			(stroke
				(width 0.1)
				(type default)
			)
			(layer "B.Fab")
		)
		(pad "1" smd circle
			(at 0.40005 0 180)
			(size 0 0)
			(layers "B.Cu" "B.Mask" "B.Paste")
			(net "P1V2_AUX")
		)
		(pad "2" smd circle
			(at -0.40005 0 180)
			(size 0 0)
			(layers "B.Cu" "B.Mask" "B.Paste")
			(net "GND")
		)
	)
	(footprint ""
		(layer "B.Cu")
		(at 313.734958 -201.926952 90)
		(property "Reference" "R28"
			(at 0 0 90)
			(layer "B.SilkS")
			(hide yes)
			(effects
				(font
					(size 1.27 1.27)
				)
				(justify mirror)
			)
		)
		(property "Value" ""
			(at 0 0 90)
			(layer "B.Fab")
			(effects
				(font
					(size 1.27 1.27)
				)
				(justify mirror)
			)
		)
		(duplicate_pad_numbers_are_jumpers no)
		(fp_line
			(start 0.7874 -0.4064)
			(end -0.7874 -0.4064)
			(stroke
				(width 0.1524)
				(type default)
			)
			(layer "B.SilkS")
		)
		(fp_line
			(start -0.7874 -0.4064)
			(end -0.7874 0.4064)
			(stroke
				(width 0.1524)
				(type default)
			)
			(layer "B.SilkS")
		)
		(fp_line
			(start 0.7874 0.4064)
			(end 0.7874 -0.4064)
			(stroke
				(width 0.1524)
				(type default)
			)
			(layer "B.SilkS")
		)
		(fp_line
			(start -0.7874 0.4064)
			(end 0.7874 0.4064)
			(stroke
				(width 0.1524)
				(type default)
			)
			(layer "B.SilkS")
		)
		(fp_line
			(start 0.67945 -0.305054)
			(end 0.12065 -0.305054)
			(stroke
				(width 0.1)
				(type default)
			)
			(layer "B.Fab")
		)
		(fp_line
			(start 0.12065 -0.305054)
			(end 0.12065 -0.2794)
			(stroke
				(width 0.1)
				(type default)
			)
			(layer "B.Fab")
		)
		(fp_line
			(start -0.12065 -0.3048)
			(end -0.67945 -0.3048)
			(stroke
				(width 0.1)
				(type default)
			)
			(layer "B.Fab")
		)
		(fp_line
			(start -0.67945 -0.3048)
			(end -0.67945 0.3048)
			(stroke
				(width 0.1)
				(type default)
			)
			(layer "B.Fab")
		)
		(fp_line
			(start 0.12065 -0.2794)
			(end -0.12065 -0.2794)
			(stroke
				(width 0.1)
				(type default)
			)
			(layer "B.Fab")
		)
		(fp_line
			(start -0.12065 -0.2794)
			(end -0.12065 -0.3048)
			(stroke
				(width 0.1)
				(type default)
			)
			(layer "B.Fab")
		)
		(fp_line
			(start 0.12065 0.2794)
			(end 0.12065 0.3048)
			(stroke
				(width 0.1)
				(type default)
			)
			(layer "B.Fab")
		)
		(fp_line
			(start -0.120396 0.2794)
			(end 0.12065 0.2794)
			(stroke
				(width 0.1)
				(type default)
			)
			(layer "B.Fab")
		)
		(fp_line
			(start 0.67945 0.3048)
			(end 0.67945 -0.305054)
			(stroke
				(width 0.1)
				(type default)
			)
			(layer "B.Fab")
		)
		(fp_line
			(start 0.12065 0.3048)
			(end 0.67945 0.3048)
			(stroke
				(width 0.1)
				(type default)
			)
			(layer "B.Fab")
		)
		(fp_line
			(start -0.120396 0.3048)
			(end -0.120396 0.2794)
			(stroke
				(width 0.1)
				(type default)
			)
			(layer "B.Fab")
		)
		(fp_line
			(start -0.67945 0.3048)
			(end -0.120396 0.3048)
			(stroke
				(width 0.1)
				(type default)
			)
			(layer "B.Fab")
		)
		(pad "1" smd circle
			(at 0.40005 0 270)
			(size 0 0)
			(layers "B.Cu" "B.Mask" "B.Paste")
			(net "SMB_CPU0_2_R_SDA")
		)
		(pad "2" smd circle
			(at -0.40005 0 270)
			(size 0 0)
			(layers "B.Cu" "B.Mask" "B.Paste")
			(net "SMB_CPU0_2_SDA")
		)
	)
	(footprint ""
		(layer "B.Cu")
		(at 234.286298 -213.258654 180)
		(property "Reference" "R281"
			(at 0 0 0)
			(layer "B.SilkS")
			(hide yes)
			(effects
				(font
					(size 1.27 1.27)
				)
				(justify mirror)
			)
		)
		(property "Value" ""
			(at 0 0 0)
			(layer "B.Fab")
			(effects
				(font
					(size 1.27 1.27)
				)
				(justify mirror)
			)
		)
		(duplicate_pad_numbers_are_jumpers no)
		(fp_line
			(start 0.7874 0.4064)
			(end 0.7874 -0.4064)
			(stroke
				(width 0.1524)
				(type default)
			)
			(layer "B.SilkS")
		)
		(fp_line
			(start 0.7874 -0.4064)
			(end -0.7874 -0.4064)
			(stroke
				(width 0.1524)
				(type default)
			)
			(layer "B.SilkS")
		)
		(fp_line
			(start -0.7874 0.4064)
			(end 0.7874 0.4064)
			(stroke
				(width 0.1524)
				(type default)
			)
			(layer "B.SilkS")
		)
		(fp_line
			(start -0.7874 -0.4064)
			(end -0.7874 0.4064)
			(stroke
				(width 0.1524)
				(type default)
			)
			(layer "B.SilkS")
		)
		(fp_line
			(start 0.67945 0.3048)
			(end 0.67945 -0.305054)
			(stroke
				(width 0.1)
				(type default)
			)
			(layer "B.Fab")
		)
		(fp_line
			(start 0.67945 -0.305054)
			(end 0.12065 -0.305054)
			(stroke
				(width 0.1)
				(type default)
			)
			(layer "B.Fab")
		)
		(fp_line
			(start 0.12065 0.3048)
			(end 0.67945 0.3048)
			(stroke
				(width 0.1)
				(type default)
			)
			(layer "B.Fab")
		)
		(fp_line
			(start 0.12065 0.2794)
			(end 0.12065 0.3048)
			(stroke
				(width 0.1)
				(type default)
			)
			(layer "B.Fab")
		)
		(fp_line
			(start 0.12065 -0.2794)
			(end -0.12065 -0.2794)
			(stroke
				(width 0.1)
				(type default)
			)
			(layer "B.Fab")
		)
		(fp_line
			(start 0.12065 -0.305054)
			(end 0.12065 -0.2794)
			(stroke
				(width 0.1)
				(type default)
			)
			(layer "B.Fab")
		)
		(fp_line
			(start -0.120396 0.3048)
			(end -0.120396 0.2794)
			(stroke
				(width 0.1)
				(type default)
			)
			(layer "B.Fab")
		)
		(fp_line
			(start -0.120396 0.2794)
			(end 0.12065 0.2794)
			(stroke
				(width 0.1)
				(type default)
			)
			(layer "B.Fab")
		)
		(fp_line
			(start -0.12065 -0.2794)
			(end -0.12065 -0.3048)
			(stroke
				(width 0.1)
				(type default)
			)
			(layer "B.Fab")
		)
		(fp_line
			(start -0.12065 -0.3048)
			(end -0.67945 -0.3048)
			(stroke
				(width 0.1)
				(type default)
			)
			(layer "B.Fab")
		)
		(fp_line
			(start -0.67945 0.3048)
			(end -0.120396 0.3048)
			(stroke
				(width 0.1)
				(type default)
			)
			(layer "B.Fab")
		)
		(fp_line
			(start -0.67945 -0.3048)
			(end -0.67945 0.3048)
			(stroke
				(width 0.1)
				(type default)
			)
			(layer "B.Fab")
		)
		(pad "1" smd rect
			(at 0.40005 0 180)
			(size 0.4572 0.508)
			(layers "B.Cu" "B.Mask" "B.Paste")
			(net "SMB_CPU0_CPU1_APML_BUF2_SDA_R2")
		)
		(pad "2" smd rect
			(at -0.40005 0 180)
			(size 0.4572 0.508)
			(layers "B.Cu" "B.Mask" "B.Paste")
			(net "SMB_CPU0_CPU1_APML_SDA_R2")
		)
	)
	(footprint ""
		(layer "B.Cu")
		(at 118.218458 -388.011162 -90)
		(property "Reference" "C477"
			(at 0 0 90)
			(layer "B.SilkS")
			(hide yes)
			(effects
				(font
					(size 1.27 1.27)
				)
				(justify mirror)
			)
		)
		(property "Value" ""
			(at 0 0 90)
			(layer "B.Fab")
			(effects
				(font
					(size 1.27 1.27)
				)
				(justify mirror)
			)
		)
		(duplicate_pad_numbers_are_jumpers no)
		(fp_line
			(start -0.299974 0.150114)
			(end 0.299974 0.150114)
			(stroke
				(width 0.1)
				(type default)
			)
			(layer "B.Fab")
		)
		(fp_line
			(start 0.299974 0.150114)
			(end 0.299974 -0.150114)
			(stroke
				(width 0.1)
				(type default)
			)
			(layer "B.Fab")
		)
		(fp_line
			(start -0.299974 -0.150114)
			(end -0.299974 0.150114)
			(stroke
				(width 0.1)
				(type default)
			)
			(layer "B.Fab")
		)
		(fp_line
			(start 0.299974 -0.150114)
			(end -0.299974 -0.150114)
			(stroke
				(width 0.1)
				(type default)
			)
			(layer "B.Fab")
		)
		(pad "1" smd rect
			(at 0.2667 0 90)
			(size 0.3048 0.381)
			(layers "B.Cu" "B.Mask" "B.Paste")
			(net "P0V9_CPU1_RT3_2A")
		)
		(pad "2" smd rect
			(at -0.2667 0 90)
			(size 0.3048 0.381)
			(layers "B.Cu" "B.Mask" "B.Paste")
			(net "GND")
		)
	)
	(footprint ""
		(layer "B.Cu")
		(at 345.51874 -398.942052 90)
		(property "Reference" "C595"
			(at 0 0 90)
			(layer "B.SilkS")
			(hide yes)
			(effects
				(font
					(size 1.27 1.27)
				)
				(justify mirror)
			)
		)
		(property "Value" ""
			(at 0 0 90)
			(layer "B.Fab")
			(effects
				(font
					(size 1.27 1.27)
				)
				(justify mirror)
			)
		)
		(duplicate_pad_numbers_are_jumpers no)
		(fp_line
			(start 0.7874 -0.4064)
			(end -0.7874 -0.4064)
			(stroke
				(width 0.1524)
				(type default)
			)
			(layer "B.SilkS")
		)
		(fp_line
			(start -0.7874 -0.4064)
			(end -0.7874 0.4064)
			(stroke
				(width 0.1524)
				(type default)
			)
			(layer "B.SilkS")
		)
		(fp_line
			(start 0.7874 0.4064)
			(end 0.7874 -0.4064)
			(stroke
				(width 0.1524)
				(type default)
			)
			(layer "B.SilkS")
		)
		(fp_line
			(start -0.7874 0.4064)
			(end 0.7874 0.4064)
			(stroke
				(width 0.1524)
				(type default)
			)
			(layer "B.SilkS")
		)
		(fp_line
			(start 0.67945 -0.305054)
			(end 0.12065 -0.305054)
			(stroke
				(width 0.1)
				(type default)
			)
			(layer "B.Fab")
		)
		(fp_line
			(start 0.12065 -0.305054)
			(end 0.12065 -0.2794)
			(stroke
				(width 0.1)
				(type default)
			)
			(layer "B.Fab")
		)
		(fp_line
			(start -0.12065 -0.3048)
			(end -0.67945 -0.3048)
			(stroke
				(width 0.1)
				(type default)
			)
			(layer "B.Fab")
		)
		(fp_line
			(start -0.67945 -0.3048)
			(end -0.67945 0.3048)
			(stroke
				(width 0.1)
				(type default)
			)
			(layer "B.Fab")
		)
		(fp_line
			(start 0.12065 -0.2794)
			(end -0.12065 -0.2794)
			(stroke
				(width 0.1)
				(type default)
			)
			(layer "B.Fab")
		)
		(fp_line
			(start -0.12065 -0.2794)
			(end -0.12065 -0.3048)
			(stroke
				(width 0.1)
				(type default)
			)
			(layer "B.Fab")
		)
		(fp_line
			(start 0.12065 0.2794)
			(end 0.12065 0.3048)
			(stroke
				(width 0.1)
				(type default)
			)
			(layer "B.Fab")
		)
		(fp_line
			(start -0.120396 0.2794)
			(end 0.12065 0.2794)
			(stroke
				(width 0.1)
				(type default)
			)
			(layer "B.Fab")
		)
		(fp_line
			(start 0.67945 0.3048)
			(end 0.67945 -0.305054)
			(stroke
				(width 0.1)
				(type default)
			)
			(layer "B.Fab")
		)
		(fp_line
			(start 0.12065 0.3048)
			(end 0.67945 0.3048)
			(stroke
				(width 0.1)
				(type default)
			)
			(layer "B.Fab")
		)
		(fp_line
			(start -0.120396 0.3048)
			(end -0.120396 0.2794)
			(stroke
				(width 0.1)
				(type default)
			)
			(layer "B.Fab")
		)
		(fp_line
			(start -0.67945 0.3048)
			(end -0.120396 0.3048)
			(stroke
				(width 0.1)
				(type default)
			)
			(layer "B.Fab")
		)
		(pad "1" smd circle
			(at 0.40005 0 270)
			(size 0 0)
			(layers "B.Cu" "B.Mask" "B.Paste")
			(net "P1V8_CPU0_RT1_1A")
		)
		(pad "2" smd circle
			(at -0.40005 0 270)
			(size 0 0)
			(layers "B.Cu" "B.Mask" "B.Paste")
			(net "GND")
		)
	)
	(footprint ""
		(layer "B.Cu")
		(at 243.713 -325.882 180)
		(property "Reference" "R1228"
			(at 0 0 0)
			(layer "B.SilkS")
			(hide yes)
			(effects
				(font
					(size 1.27 1.27)
				)
				(justify mirror)
			)
		)
		(property "Value" ""
			(at 0 0 0)
			(layer "B.Fab")
			(effects
				(font
					(size 1.27 1.27)
				)
				(justify mirror)
			)
		)
		(duplicate_pad_numbers_are_jumpers no)
		(fp_line
			(start 0.7874 0.4064)
			(end 0.7874 -0.4064)
			(stroke
				(width 0.1524)
				(type default)
			)
			(layer "B.SilkS")
		)
		(fp_line
			(start 0.7874 -0.4064)
			(end -0.7874 -0.4064)
			(stroke
				(width 0.1524)
				(type default)
			)
			(layer "B.SilkS")
		)
		(fp_line
			(start -0.7874 0.4064)
			(end 0.7874 0.4064)
			(stroke
				(width 0.1524)
				(type default)
			)
			(layer "B.SilkS")
		)
		(fp_line
			(start -0.7874 -0.4064)
			(end -0.7874 0.4064)
			(stroke
				(width 0.1524)
				(type default)
			)
			(layer "B.SilkS")
		)
		(fp_line
			(start 0.67945 0.3048)
			(end 0.67945 -0.305054)
			(stroke
				(width 0.1)
				(type default)
			)
			(layer "B.Fab")
		)
		(fp_line
			(start 0.67945 -0.305054)
			(end 0.12065 -0.305054)
			(stroke
				(width 0.1)
				(type default)
			)
			(layer "B.Fab")
		)
		(fp_line
			(start 0.12065 0.3048)
			(end 0.67945 0.3048)
			(stroke
				(width 0.1)
				(type default)
			)
			(layer "B.Fab")
		)
		(fp_line
			(start 0.12065 0.2794)
			(end 0.12065 0.3048)
			(stroke
				(width 0.1)
				(type default)
			)
			(layer "B.Fab")
		)
		(fp_line
			(start 0.12065 -0.2794)
			(end -0.12065 -0.2794)
			(stroke
				(width 0.1)
				(type default)
			)
			(layer "B.Fab")
		)
		(fp_line
			(start 0.12065 -0.305054)
			(end 0.12065 -0.2794)
			(stroke
				(width 0.1)
				(type default)
			)
			(layer "B.Fab")
		)
		(fp_line
			(start -0.120396 0.3048)
			(end -0.120396 0.2794)
			(stroke
				(width 0.1)
				(type default)
			)
			(layer "B.Fab")
		)
		(fp_line
			(start -0.120396 0.2794)
			(end 0.12065 0.2794)
			(stroke
				(width 0.1)
				(type default)
			)
			(layer "B.Fab")
		)
		(fp_line
			(start -0.12065 -0.2794)
			(end -0.12065 -0.3048)
			(stroke
				(width 0.1)
				(type default)
			)
			(layer "B.Fab")
		)
		(fp_line
			(start -0.12065 -0.3048)
			(end -0.67945 -0.3048)
			(stroke
				(width 0.1)
				(type default)
			)
			(layer "B.Fab")
		)
		(fp_line
			(start -0.67945 0.3048)
			(end -0.120396 0.3048)
			(stroke
				(width 0.1)
				(type default)
			)
			(layer "B.Fab")
		)
		(fp_line
			(start -0.67945 -0.3048)
			(end -0.67945 0.3048)
			(stroke
				(width 0.1)
				(type default)
			)
			(layer "B.Fab")
		)
		(pad "1" smd circle
			(at 0.40005 0)
			(size 0 0)
			(layers "B.Cu" "B.Mask" "B.Paste")
			(net "SMB_ADC_SCL_R")
		)
		(pad "2" smd circle
			(at -0.40005 0)
			(size 0 0)
			(layers "B.Cu" "B.Mask" "B.Paste")
			(net "SMB_SEN_MAM_2_3V3AUX_SCL")
		)
	)
)
